FILE_TYPE = CONNECTIVITY;
{Allegro Design Entry HDL 17.4-2019 S026 (4007227) 1/17/2022}
"PAGE_NUMBER" = 367;
0"NC";
END.
